# S9S_MB_2U (Grand Teton) — schematic netlist excerpt (pin names and nets, part order shuffled) for the footprints in the layout excerpt that follows; sources: Cadence DE-HDL packaged netlist, KiCad conversion of 03242023_DA0F0TMBIJ0_F0T_Motherboard_J_brd_V01_OCP.brd

C1963  Q_CAP  0.1UF 25V 10% X7R  pkg 0402  page 150 : A = P3V3_AUX ; B = GND
R1401  Q_RES  10K 1% CHIP  pkg 0402LF  page 220 : A = PU_MAIN_FPGA_CONFIG_DONE ; B = P3V3_AUX

(kicad_pcb
	(version 20260206)
	(generator "pcbnew")
	(generator_version "10.0")
	(general
		(thickness 1.6)
		(legacy_teardrops no)
	)
	(paper "A4")
	(title_block
		(title "03242023_DA0F0TMBIJ0_F0T_Motherboard_J_brd_V01_OCP.brd")
		(comment 1 "Grand Teton / footprints 1699-1700 of 6105")
	)
	(layers
		(0 "F.Cu" signal "TOP")
		(4 "In1.Cu" signal "GND")
		(6 "In2.Cu" signal "IN1")
		(8 "In3.Cu" signal "GND1")
		(10 "In4.Cu" signal "IN2")
		(12 "In5.Cu" signal "GND2")
		(14 "In6.Cu" signal "IN3")
		(16 "In7.Cu" signal "GND3")
		(18 "In8.Cu" signal "VCC")
		(20 "In9.Cu" signal "VCC1")
		(22 "In10.Cu" signal "GND4")
		(24 "In11.Cu" signal "IN4")
		(26 "In12.Cu" signal "GND5")
		(28 "In13.Cu" signal "IN5")
		(30 "In14.Cu" signal "GND6")
		(32 "In15.Cu" signal "IN6")
		(34 "In16.Cu" signal "GND7")
		(2 "B.Cu" signal "BOTTOM")
		(9 "F.Adhes" user "F.Adhesive")
		(11 "B.Adhes" user "B.Adhesive")
		(13 "F.Paste" user "Package Geometry/Pastemask Top")
		(15 "B.Paste" user "Package Geometry/Pastemask Bottom")
		(5 "F.SilkS" user "Ref Des/Silkscreen Top")
		(7 "B.SilkS" user "Ref Des/Silkscreen Bottom")
		(1 "F.Mask" user "Board Geometry/Soldermask Top")
		(3 "B.Mask" user "Board Geometry/Soldermask Bottom")
		(17 "Dwgs.User" user "User.Drawings")
		(19 "Cmts.User" user "User.Comments")
		(21 "Eco1.User" user "User.Eco1")
		(23 "Eco2.User" user "User.Eco2")
		(25 "Edge.Cuts" user "Board Geometry/Outline")
		(27 "Margin" user)
		(31 "F.CrtYd" user "Package Geometry/Place Bound Top")
		(29 "B.CrtYd" user "Package Geometry/Place Bound Bottom")
		(35 "F.Fab" user "Ref Des/Assembly Top")
		(33 "B.Fab" user "Ref Des/Assembly Bottom")
	)
	(footprint ""
		(layer "F.Cu")
		(at 164.64788 -121.376948 180)
		(property "Reference" "R1401"
			(at 0 0 180)
			(layer "F.SilkS")
			(hide yes)
			(effects
				(font
					(size 1.27 1.27)
				)
			)
		)
		(property "Value" ""
			(at 0 0 180)
			(layer "F.Fab")
			(effects
				(font
					(size 1.27 1.27)
				)
			)
		)
		(duplicate_pad_numbers_are_jumpers no)
		(fp_line
			(start 0.7874 0.4064)
			(end -0.7874 0.4064)
			(stroke
				(width 0.1524)
				(type default)
			)
			(layer "F.SilkS")
		)
		(fp_line
			(start 0.7874 -0.4064)
			(end 0.7874 0.4064)
			(stroke
				(width 0.1524)
				(type default)
			)
			(layer "F.SilkS")
		)
		(fp_line
			(start -0.7874 0.4064)
			(end -0.7874 -0.4064)
			(stroke
				(width 0.1524)
				(type default)
			)
			(layer "F.SilkS")
		)
		(fp_line
			(start -0.7874 -0.4064)
			(end 0.7874 -0.4064)
			(stroke
				(width 0.1524)
				(type default)
			)
			(layer "F.SilkS")
		)
		(fp_line
			(start 0.67945 0.3048)
			(end 0.120396 0.3048)
			(stroke
				(width 0.1)
				(type default)
			)
			(layer "F.Fab")
		)
		(fp_line
			(start 0.67945 -0.3048)
			(end 0.67945 0.3048)
			(stroke
				(width 0.1)
				(type default)
			)
			(layer "F.Fab")
		)
		(fp_line
			(start 0.12065 -0.2794)
			(end 0.12065 -0.3048)
			(stroke
				(width 0.1)
				(type default)
			)
			(layer "F.Fab")
		)
		(fp_line
			(start 0.12065 -0.3048)
			(end 0.67945 -0.3048)
			(stroke
				(width 0.1)
				(type default)
			)
			(layer "F.Fab")
		)
		(fp_line
			(start 0.120396 0.3048)
			(end 0.120396 0.2794)
			(stroke
				(width 0.1)
				(type default)
			)
			(layer "F.Fab")
		)
		(fp_line
			(start 0.120396 0.2794)
			(end -0.12065 0.2794)
			(stroke
				(width 0.1)
				(type default)
			)
			(layer "F.Fab")
		)
		(fp_line
			(start -0.12065 0.3048)
			(end -0.67945 0.3048)
			(stroke
				(width 0.1)
				(type default)
			)
			(layer "F.Fab")
		)
		(fp_line
			(start -0.12065 0.2794)
			(end -0.12065 0.3048)
			(stroke
				(width 0.1)
				(type default)
			)
			(layer "F.Fab")
		)
		(fp_line
			(start -0.12065 -0.2794)
			(end 0.12065 -0.2794)
			(stroke
				(width 0.1)
				(type default)
			)
			(layer "F.Fab")
		)
		(fp_line
			(start -0.12065 -0.305054)
			(end -0.12065 -0.2794)
			(stroke
				(width 0.1)
				(type default)
			)
			(layer "F.Fab")
		)
		(fp_line
			(start -0.67945 0.3048)
			(end -0.67945 -0.305054)
			(stroke
				(width 0.1)
				(type default)
			)
			(layer "F.Fab")
		)
		(fp_line
			(start -0.67945 -0.305054)
			(end -0.12065 -0.305054)
			(stroke
				(width 0.1)
				(type default)
			)
			(layer "F.Fab")
		)
		(pad "1" smd circle
			(at -0.40005 0 180)
			(size 0 0)
			(layers "F.Cu" "F.Mask" "F.Paste")
			(net "PU_MAIN_FPGA_CONFIG_DONE")
		)
		(pad "2" smd circle
			(at 0.40005 0 180)
			(size 0 0)
			(layers "F.Cu" "F.Mask" "F.Paste")
			(net "P3V3_AUX")
		)
	)
	(footprint ""
		(layer "F.Cu")
		(at 103.1367 -393.685268 180)
		(property "Reference" "C1963"
			(at 0 0 180)
			(layer "F.SilkS")
			(hide yes)
			(effects
				(font
					(size 1.27 1.27)
				)
			)
		)
		(property "Value" ""
			(at 0 0 180)
			(layer "F.Fab")
			(effects
				(font
					(size 1.27 1.27)
				)
			)
		)
		(duplicate_pad_numbers_are_jumpers no)
		(fp_line
			(start 0.7874 0.4064)
			(end -0.7874 0.4064)
			(stroke
				(width 0.1524)
				(type default)
			)
			(layer "F.SilkS")
		)
		(fp_line
			(start 0.7874 -0.4064)
			(end 0.7874 0.4064)
			(stroke
				(width 0.1524)
				(type default)
			)
			(layer "F.SilkS")
		)
		(fp_line
			(start -0.7874 0.4064)
			(end -0.7874 -0.4064)
			(stroke
				(width 0.1524)
				(type default)
			)
			(layer "F.SilkS")
		)
		(fp_line
			(start -0.7874 -0.4064)
			(end 0.7874 -0.4064)
			(stroke
				(width 0.1524)
				(type default)
			)
			(layer "F.SilkS")
		)
		(fp_line
			(start 0.67945 0.3048)
			(end 0.120396 0.3048)
			(stroke
				(width 0.1)
				(type default)
			)
			(layer "F.Fab")
		)
		(fp_line
			(start 0.67945 -0.3048)
			(end 0.67945 0.3048)
			(stroke
				(width 0.1)
				(type default)
			)
			(layer "F.Fab")
		)
		(fp_line
			(start 0.12065 -0.2794)
			(end 0.12065 -0.3048)
			(stroke
				(width 0.1)
				(type default)
			)
			(layer "F.Fab")
		)
		(fp_line
			(start 0.12065 -0.3048)
			(end 0.67945 -0.3048)
			(stroke
				(width 0.1)
				(type default)
			)
			(layer "F.Fab")
		)
		(fp_line
			(start 0.120396 0.3048)
			(end 0.120396 0.2794)
			(stroke
				(width 0.1)
				(type default)
			)
			(layer "F.Fab")
		)
		(fp_line
			(start 0.120396 0.2794)
			(end -0.12065 0.2794)
			(stroke
				(width 0.1)
				(type default)
			)
			(layer "F.Fab")
		)
		(fp_line
			(start -0.12065 0.3048)
			(end -0.67945 0.3048)
			(stroke
				(width 0.1)
				(type default)
			)
			(layer "F.Fab")
		)
		(fp_line
			(start -0.12065 0.2794)
			(end -0.12065 0.3048)
			(stroke
				(width 0.1)
				(type default)
			)
			(layer "F.Fab")
		)
		(fp_line
			(start -0.12065 -0.2794)
			(end 0.12065 -0.2794)
			(stroke
				(width 0.1)
				(type default)
			)
			(layer "F.Fab")
		)
		(fp_line
			(start -0.12065 -0.305054)
			(end -0.12065 -0.2794)
			(stroke
				(width 0.1)
				(type default)
			)
			(layer "F.Fab")
		)
		(fp_line
			(start -0.67945 0.3048)
			(end -0.67945 -0.305054)
			(stroke
				(width 0.1)
				(type default)
			)
			(layer "F.Fab")
		)
		(fp_line
			(start -0.67945 -0.305054)
			(end -0.12065 -0.305054)
			(stroke
				(width 0.1)
				(type default)
			)
			(layer "F.Fab")
		)
		(pad "1" smd circle
			(at -0.40005 0 180)
			(size 0 0)
			(layers "F.Cu" "F.Mask" "F.Paste")
			(net "P3V3_AUX")
		)
		(pad "2" smd circle
			(at 0.40005 0 180)
			(size 0 0)
			(layers "F.Cu" "F.Mask" "F.Paste")
			(net "GND")
		)
	)
)
